# T6G (Grand Teton) — schematic netlist excerpt (pin names and nets, part order shuffled) for the footprints in the layout excerpt that follows; sources: Cadence DE-HDL packaged netlist, KiCad conversion of 04192023_DAF0TMB3IC0_F0TG_MB_C_brd_V02_OCP.brd

C2624  Q_CAP  22UF 4V 20% X6S  pkg C0402  page 70 : A = PVDD11_S3_P0 ; B = GND
C291  Q_CAP  0.1UF 10V 10% X7S  pkg C0201  page 334 : A = P0V9_CPU1_RT1_2A ; B = GND
C174  Q_CAP  10UF 25V 10% X6S  pkg C0805  page 98 : A = P12V_MEM_CPU1 ; B = GND
C606  Q_CAP  0.1UF 10V 10% X7S  pkg C0201  page 290 : A = P1V8_CPU0_RT1_1A ; B = GND

(kicad_pcb
	(version 20260206)
	(generator "pcbnew")
	(generator_version "10.0")
	(general
		(thickness 1.6)
		(legacy_teardrops no)
	)
	(paper "A4")
	(title_block
		(title "04192023_DAF0TMB3IC0_F0TG_MB_C_brd_V02_OCP.brd")
		(comment 1 "Grand Teton / footprints 5478-5481 of 8354")
	)
	(layers
		(0 "F.Cu" signal "TOP")
		(4 "In1.Cu" signal "GND")
		(6 "In2.Cu" signal "IN1")
		(8 "In3.Cu" signal "GND1")
		(10 "In4.Cu" signal "IN2")
		(12 "In5.Cu" signal "GND2")
		(14 "In6.Cu" signal "IN3")
		(16 "In7.Cu" signal "GND3")
		(18 "In8.Cu" signal "VCC")
		(20 "In9.Cu" signal "VCC1")
		(22 "In10.Cu" signal "GND4")
		(24 "In11.Cu" signal "IN4")
		(26 "In12.Cu" signal "GND5")
		(28 "In13.Cu" signal "IN5")
		(30 "In14.Cu" signal "GND6")
		(32 "In15.Cu" signal "IN6")
		(34 "In16.Cu" signal "GND7")
		(2 "B.Cu" signal "BOTTOM")
		(9 "F.Adhes" user "F.Adhesive")
		(11 "B.Adhes" user "B.Adhesive")
		(13 "F.Paste" user "Package Geometry/Pastemask Top")
		(15 "B.Paste" user "Package Geometry/Pastemask Bottom")
		(5 "F.SilkS" user "Ref Des/Silkscreen Top")
		(7 "B.SilkS" user "Ref Des/Silkscreen Bottom")
		(1 "F.Mask" user "Board Geometry/Soldermask Top")
		(3 "B.Mask" user "Board Geometry/Soldermask Bottom")
		(17 "Dwgs.User" user "User.Drawings")
		(19 "Cmts.User" user "User.Comments")
		(21 "Eco1.User" user "User.Eco1")
		(23 "Eco2.User" user "User.Eco2")
		(25 "Edge.Cuts" user "Board Geometry/Outline")
		(27 "Margin" user)
		(31 "F.CrtYd" user "Package Geometry/Place Bound Top")
		(29 "B.CrtYd" user "Package Geometry/Place Bound Bottom")
		(35 "F.Fab" user "Ref Des/Assembly Top")
		(33 "B.Fab" user "Ref Des/Assembly Bottom")
	)
	(footprint ""
		(layer "B.Cu")
		(at 363.645958 -259.845048 180)
		(property "Reference" "C2624"
			(at 0 0 0)
			(layer "B.SilkS")
			(hide yes)
			(effects
				(font
					(size 1.27 1.27)
				)
				(justify mirror)
			)
		)
		(property "Value" ""
			(at 0 0 0)
			(layer "B.Fab")
			(effects
				(font
					(size 1.27 1.27)
				)
				(justify mirror)
			)
		)
		(duplicate_pad_numbers_are_jumpers no)
		(fp_line
			(start 0.7874 0.4064)
			(end 0.7874 -0.4064)
			(stroke
				(width 0.1524)
				(type default)
			)
			(layer "B.SilkS")
		)
		(fp_line
			(start 0.7874 -0.4064)
			(end -0.7874 -0.4064)
			(stroke
				(width 0.1524)
				(type default)
			)
			(layer "B.SilkS")
		)
		(fp_line
			(start -0.7874 0.4064)
			(end 0.7874 0.4064)
			(stroke
				(width 0.1524)
				(type default)
			)
			(layer "B.SilkS")
		)
		(fp_line
			(start -0.7874 -0.4064)
			(end -0.7874 0.4064)
			(stroke
				(width 0.1524)
				(type default)
			)
			(layer "B.SilkS")
		)
		(fp_line
			(start 0.67945 0.3048)
			(end 0.67945 -0.305054)
			(stroke
				(width 0.1)
				(type default)
			)
			(layer "B.Fab")
		)
		(fp_line
			(start 0.67945 -0.305054)
			(end 0.12065 -0.305054)
			(stroke
				(width 0.1)
				(type default)
			)
			(layer "B.Fab")
		)
		(fp_line
			(start 0.12065 0.3048)
			(end 0.67945 0.3048)
			(stroke
				(width 0.1)
				(type default)
			)
			(layer "B.Fab")
		)
		(fp_line
			(start 0.12065 0.2794)
			(end 0.12065 0.3048)
			(stroke
				(width 0.1)
				(type default)
			)
			(layer "B.Fab")
		)
		(fp_line
			(start 0.12065 -0.2794)
			(end -0.12065 -0.2794)
			(stroke
				(width 0.1)
				(type default)
			)
			(layer "B.Fab")
		)
		(fp_line
			(start 0.12065 -0.305054)
			(end 0.12065 -0.2794)
			(stroke
				(width 0.1)
				(type default)
			)
			(layer "B.Fab")
		)
		(fp_line
			(start -0.120396 0.3048)
			(end -0.120396 0.2794)
			(stroke
				(width 0.1)
				(type default)
			)
			(layer "B.Fab")
		)
		(fp_line
			(start -0.120396 0.2794)
			(end 0.12065 0.2794)
			(stroke
				(width 0.1)
				(type default)
			)
			(layer "B.Fab")
		)
		(fp_line
			(start -0.12065 -0.2794)
			(end -0.12065 -0.3048)
			(stroke
				(width 0.1)
				(type default)
			)
			(layer "B.Fab")
		)
		(fp_line
			(start -0.12065 -0.3048)
			(end -0.67945 -0.3048)
			(stroke
				(width 0.1)
				(type default)
			)
			(layer "B.Fab")
		)
		(fp_line
			(start -0.67945 0.3048)
			(end -0.120396 0.3048)
			(stroke
				(width 0.1)
				(type default)
			)
			(layer "B.Fab")
		)
		(fp_line
			(start -0.67945 -0.3048)
			(end -0.67945 0.3048)
			(stroke
				(width 0.1)
				(type default)
			)
			(layer "B.Fab")
		)
		(pad "1" smd circle
			(at 0.40005 0)
			(size 0 0)
			(layers "B.Cu" "B.Mask" "B.Paste")
			(net "PVDD11_S3_P0")
		)
		(pad "2" smd circle
			(at -0.40005 0)
			(size 0 0)
			(layers "B.Cu" "B.Mask" "B.Paste")
			(net "GND")
		)
	)
	(footprint ""
		(layer "B.Cu")
		(at 345.645994 -396.393162 -90)
		(property "Reference" "C606"
			(at 0 0 90)
			(layer "B.SilkS")
			(hide yes)
			(effects
				(font
					(size 1.27 1.27)
				)
				(justify mirror)
			)
		)
		(property "Value" ""
			(at 0 0 90)
			(layer "B.Fab")
			(effects
				(font
					(size 1.27 1.27)
				)
				(justify mirror)
			)
		)
		(duplicate_pad_numbers_are_jumpers no)
		(fp_line
			(start -0.299974 0.150114)
			(end 0.299974 0.150114)
			(stroke
				(width 0.1)
				(type default)
			)
			(layer "B.Fab")
		)
		(fp_line
			(start 0.299974 0.150114)
			(end 0.299974 -0.150114)
			(stroke
				(width 0.1)
				(type default)
			)
			(layer "B.Fab")
		)
		(fp_line
			(start -0.299974 -0.150114)
			(end -0.299974 0.150114)
			(stroke
				(width 0.1)
				(type default)
			)
			(layer "B.Fab")
		)
		(fp_line
			(start 0.299974 -0.150114)
			(end -0.299974 -0.150114)
			(stroke
				(width 0.1)
				(type default)
			)
			(layer "B.Fab")
		)
		(pad "1" smd rect
			(at 0.2667 0 90)
			(size 0.3048 0.381)
			(layers "B.Cu" "B.Mask" "B.Paste")
			(net "P1V8_CPU0_RT1_1A")
		)
		(pad "2" smd rect
			(at -0.2667 0 90)
			(size 0.3048 0.381)
			(layers "B.Cu" "B.Mask" "B.Paste")
			(net "GND")
		)
	)
	(footprint ""
		(layer "B.Cu")
		(at 59.428126 -192.66027)
		(property "Reference" "C174"
			(at 0 0 0)
			(layer "B.SilkS")
			(hide yes)
			(effects
				(font
					(size 1.27 1.27)
				)
				(justify mirror)
			)
		)
		(property "Value" ""
			(at 0 0 0)
			(layer "B.Fab")
			(effects
				(font
					(size 1.27 1.27)
				)
				(justify mirror)
			)
		)
		(duplicate_pad_numbers_are_jumpers no)
		(fp_line
			(start -1.524 -0.762)
			(end -1.524 0.762)
			(stroke
				(width 0.1524)
				(type default)
			)
			(layer "B.SilkS")
		)
		(fp_line
			(start -1.524 0.762)
			(end 1.524 0.762)
			(stroke
				(width 0.1524)
				(type default)
			)
			(layer "B.SilkS")
		)
		(fp_line
			(start 1.524 -0.762)
			(end -1.524 -0.762)
			(stroke
				(width 0.1524)
				(type default)
			)
			(layer "B.SilkS")
		)
		(fp_line
			(start 1.524 0.762)
			(end 1.524 -0.762)
			(stroke
				(width 0.1524)
				(type default)
			)
			(layer "B.SilkS")
		)
		(fp_line
			(start -1.1049 -0.724916)
			(end 1.1049 -0.724916)
			(stroke
				(width 0.1)
				(type default)
			)
			(layer "B.Fab")
		)
		(fp_line
			(start -1.1049 0.724916)
			(end -1.1049 -0.724916)
			(stroke
				(width 0.1)
				(type default)
			)
			(layer "B.Fab")
		)
		(fp_line
			(start 1.1049 -0.724916)
			(end 1.1049 0.724916)
			(stroke
				(width 0.1)
				(type default)
			)
			(layer "B.Fab")
		)
		(fp_line
			(start 1.1049 0.724916)
			(end -1.1049 0.724916)
			(stroke
				(width 0.1)
				(type default)
			)
			(layer "B.Fab")
		)
		(pad "1" smd rect
			(at 0.889 0)
			(size 1.016 1.27)
			(layers "B.Cu" "B.Mask" "B.Paste")
			(net "P12V_MEM_CPU1")
		)
		(pad "2" smd rect
			(at -0.889 0)
			(size 1.016 1.27)
			(layers "B.Cu" "B.Mask" "B.Paste")
			(net "GND")
		)
	)
	(footprint ""
		(layer "B.Cu")
		(at 98.046286 -388.011162 -90)
		(property "Reference" "C291"
			(at 0 0 90)
			(layer "B.SilkS")
			(hide yes)
			(effects
				(font
					(size 1.27 1.27)
				)
				(justify mirror)
			)
		)
		(property "Value" ""
			(at 0 0 90)
			(layer "B.Fab")
			(effects
				(font
					(size 1.27 1.27)
				)
				(justify mirror)
			)
		)
		(duplicate_pad_numbers_are_jumpers no)
		(fp_line
			(start -0.299974 0.150114)
			(end 0.299974 0.150114)
			(stroke
				(width 0.1)
				(type default)
			)
			(layer "B.Fab")
		)
		(fp_line
			(start 0.299974 0.150114)
			(end 0.299974 -0.150114)
			(stroke
				(width 0.1)
				(type default)
			)
			(layer "B.Fab")
		)
		(fp_line
			(start -0.299974 -0.150114)
			(end -0.299974 0.150114)
			(stroke
				(width 0.1)
				(type default)
			)
			(layer "B.Fab")
		)
		(fp_line
			(start 0.299974 -0.150114)
			(end -0.299974 -0.150114)
			(stroke
				(width 0.1)
				(type default)
			)
			(layer "B.Fab")
		)
		(pad "1" smd rect
			(at 0.2667 0 90)
			(size 0.3048 0.381)
			(layers "B.Cu" "B.Mask" "B.Paste")
			(net "P0V9_CPU1_RT1_2A")
		)
		(pad "2" smd rect
			(at -0.2667 0 90)
			(size 0.3048 0.381)
			(layers "B.Cu" "B.Mask" "B.Paste")
			(net "GND")
		)
	)
)
